# S9S_MB_2U (Grand Teton) — schematic netlist excerpt (pin names and nets, part order shuffled) for the footprints in the layout excerpt that follows; sources: Cadence DE-HDL packaged netlist, KiCad conversion of 03242023_DA0F0TMBIJ0_F0T_Motherboard_J_brd_V01_OCP.brd

C225  Q_CAP  47UF 4V 20% X6S  pkg C0805  page 77 : A = PVCCIN_CPU1 ; B = GND
C424  Q_CAP  22UF 4V 20% X6S  pkg C0402  page 77 : A = PVCCFA_EHV_FIVRA_CPU1 ; B = GND
R1316  Q_RES  200K 0.1% EMPTY  pkg 0603LF  page 179 : A = XTAL_PCH_25M_IN_R ; B = XTAL_PCH_25M_OUT

(kicad_pcb
	(version 20260206)
	(generator "pcbnew")
	(generator_version "10.0")
	(general
		(thickness 1.6)
		(legacy_teardrops no)
	)
	(paper "A4")
	(title_block
		(title "03242023_DA0F0TMBIJ0_F0T_Motherboard_J_brd_V01_OCP.brd")
		(comment 1 "Grand Teton / footprints 1703-1705 of 6105")
	)
	(layers
		(0 "F.Cu" signal "TOP")
		(4 "In1.Cu" signal "GND")
		(6 "In2.Cu" signal "IN1")
		(8 "In3.Cu" signal "GND1")
		(10 "In4.Cu" signal "IN2")
		(12 "In5.Cu" signal "GND2")
		(14 "In6.Cu" signal "IN3")
		(16 "In7.Cu" signal "GND3")
		(18 "In8.Cu" signal "VCC")
		(20 "In9.Cu" signal "VCC1")
		(22 "In10.Cu" signal "GND4")
		(24 "In11.Cu" signal "IN4")
		(26 "In12.Cu" signal "GND5")
		(28 "In13.Cu" signal "IN5")
		(30 "In14.Cu" signal "GND6")
		(32 "In15.Cu" signal "IN6")
		(34 "In16.Cu" signal "GND7")
		(2 "B.Cu" signal "BOTTOM")
		(9 "F.Adhes" user "F.Adhesive")
		(11 "B.Adhes" user "B.Adhesive")
		(13 "F.Paste" user "Package Geometry/Pastemask Top")
		(15 "B.Paste" user "Package Geometry/Pastemask Bottom")
		(5 "F.SilkS" user "Ref Des/Silkscreen Top")
		(7 "B.SilkS" user "Ref Des/Silkscreen Bottom")
		(1 "F.Mask" user "Board Geometry/Soldermask Top")
		(3 "B.Mask" user "Board Geometry/Soldermask Bottom")
		(17 "Dwgs.User" user "User.Drawings")
		(19 "Cmts.User" user "User.Comments")
		(21 "Eco1.User" user "User.Eco1")
		(23 "Eco2.User" user "User.Eco2")
		(25 "Edge.Cuts" user "Board Geometry/Outline")
		(27 "Margin" user)
		(31 "F.CrtYd" user "Package Geometry/Place Bound Top")
		(29 "B.CrtYd" user "Package Geometry/Place Bound Bottom")
		(35 "F.Fab" user "Ref Des/Assembly Top")
		(33 "B.Fab" user "Ref Des/Assembly Bottom")
	)
	(footprint ""
		(layer "F.Cu")
		(at 119.508016 -240.277142 90)
		(property "Reference" "C424"
			(at 0 0 90)
			(layer "F.SilkS")
			(hide yes)
			(effects
				(font
					(size 1.27 1.27)
				)
			)
		)
		(property "Value" ""
			(at 0 0 90)
			(layer "F.Fab")
			(effects
				(font
					(size 1.27 1.27)
				)
			)
		)
		(duplicate_pad_numbers_are_jumpers no)
		(fp_line
			(start 0.7874 -0.4064)
			(end 0.7874 0.4064)
			(stroke
				(width 0.1524)
				(type default)
			)
			(layer "F.SilkS")
		)
		(fp_line
			(start -0.7874 -0.4064)
			(end 0.7874 -0.4064)
			(stroke
				(width 0.1524)
				(type default)
			)
			(layer "F.SilkS")
		)
		(fp_line
			(start 0.7874 0.4064)
			(end -0.7874 0.4064)
			(stroke
				(width 0.1524)
				(type default)
			)
			(layer "F.SilkS")
		)
		(fp_line
			(start -0.7874 0.4064)
			(end -0.7874 -0.4064)
			(stroke
				(width 0.1524)
				(type default)
			)
			(layer "F.SilkS")
		)
		(fp_line
			(start -0.12065 -0.305054)
			(end -0.12065 -0.2794)
			(stroke
				(width 0.1)
				(type default)
			)
			(layer "F.Fab")
		)
		(fp_line
			(start -0.67945 -0.305054)
			(end -0.12065 -0.305054)
			(stroke
				(width 0.1)
				(type default)
			)
			(layer "F.Fab")
		)
		(fp_line
			(start 0.67945 -0.3048)
			(end 0.67945 0.3048)
			(stroke
				(width 0.1)
				(type default)
			)
			(layer "F.Fab")
		)
		(fp_line
			(start 0.12065 -0.3048)
			(end 0.67945 -0.3048)
			(stroke
				(width 0.1)
				(type default)
			)
			(layer "F.Fab")
		)
		(fp_line
			(start 0.12065 -0.2794)
			(end 0.12065 -0.3048)
			(stroke
				(width 0.1)
				(type default)
			)
			(layer "F.Fab")
		)
		(fp_line
			(start -0.12065 -0.2794)
			(end 0.12065 -0.2794)
			(stroke
				(width 0.1)
				(type default)
			)
			(layer "F.Fab")
		)
		(fp_line
			(start 0.120396 0.2794)
			(end -0.12065 0.2794)
			(stroke
				(width 0.1)
				(type default)
			)
			(layer "F.Fab")
		)
		(fp_line
			(start -0.12065 0.2794)
			(end -0.12065 0.3048)
			(stroke
				(width 0.1)
				(type default)
			)
			(layer "F.Fab")
		)
		(fp_line
			(start 0.67945 0.3048)
			(end 0.120396 0.3048)
			(stroke
				(width 0.1)
				(type default)
			)
			(layer "F.Fab")
		)
		(fp_line
			(start 0.120396 0.3048)
			(end 0.120396 0.2794)
			(stroke
				(width 0.1)
				(type default)
			)
			(layer "F.Fab")
		)
		(fp_line
			(start -0.12065 0.3048)
			(end -0.67945 0.3048)
			(stroke
				(width 0.1)
				(type default)
			)
			(layer "F.Fab")
		)
		(fp_line
			(start -0.67945 0.3048)
			(end -0.67945 -0.305054)
			(stroke
				(width 0.1)
				(type default)
			)
			(layer "F.Fab")
		)
		(pad "1" smd circle
			(at -0.40005 0 90)
			(size 0 0)
			(layers "F.Cu" "F.Mask" "F.Paste")
			(net "PVCCFA_EHV_FIVRA_CPU1")
		)
		(pad "2" smd circle
			(at 0.40005 0 90)
			(size 0 0)
			(layers "F.Cu" "F.Mask" "F.Paste")
			(net "GND")
		)
	)
	(footprint ""
		(layer "F.Cu")
		(at 111.74222 -296.05478 180)
		(property "Reference" "C225"
			(at 0 0 180)
			(layer "F.SilkS")
			(hide yes)
			(effects
				(font
					(size 1.27 1.27)
				)
			)
		)
		(property "Value" ""
			(at 0 0 180)
			(layer "F.Fab")
			(effects
				(font
					(size 1.27 1.27)
				)
			)
		)
		(duplicate_pad_numbers_are_jumpers no)
		(fp_line
			(start 1.524 0.762)
			(end -1.524 0.762)
			(stroke
				(width 0.1524)
				(type default)
			)
			(layer "F.SilkS")
		)
		(fp_line
			(start 1.524 -0.762)
			(end 1.524 0.762)
			(stroke
				(width 0.1524)
				(type default)
			)
			(layer "F.SilkS")
		)
		(fp_line
			(start -1.524 0.762)
			(end -1.524 -0.762)
			(stroke
				(width 0.1524)
				(type default)
			)
			(layer "F.SilkS")
		)
		(fp_line
			(start -1.524 -0.762)
			(end 1.524 -0.762)
			(stroke
				(width 0.1524)
				(type default)
			)
			(layer "F.SilkS")
		)
		(fp_line
			(start 1.1049 0.724916)
			(end 1.1049 -0.724916)
			(stroke
				(width 0.1)
				(type default)
			)
			(layer "F.Fab")
		)
		(fp_line
			(start 1.1049 -0.724916)
			(end -1.1049 -0.724916)
			(stroke
				(width 0.1)
				(type default)
			)
			(layer "F.Fab")
		)
		(fp_line
			(start -1.1049 0.724916)
			(end 1.1049 0.724916)
			(stroke
				(width 0.1)
				(type default)
			)
			(layer "F.Fab")
		)
		(fp_line
			(start -1.1049 -0.724916)
			(end -1.1049 0.724916)
			(stroke
				(width 0.1)
				(type default)
			)
			(layer "F.Fab")
		)
		(pad "1" smd rect
			(at -0.889 0)
			(size 1.016 1.27)
			(layers "F.Cu" "F.Mask" "F.Paste")
			(net "PVCCIN_CPU1")
		)
		(pad "2" smd rect
			(at 0.889 0)
			(size 1.016 1.27)
			(layers "F.Cu" "F.Mask" "F.Paste")
			(net "GND")
		)
	)
	(footprint ""
		(layer "F.Cu")
		(at 336.406998 -65.015364)
		(property "Reference" "R1316"
			(at 0 0 0)
			(layer "F.SilkS")
			(hide yes)
			(effects
				(font
					(size 1.27 1.27)
				)
			)
		)
		(property "Value" ""
			(at 0 0 0)
			(layer "F.Fab")
			(effects
				(font
					(size 1.27 1.27)
				)
			)
		)
		(duplicate_pad_numbers_are_jumpers no)
		(fp_line
			(start -1.2954 -0.5842)
			(end 1.2954 -0.5842)
			(stroke
				(width 0.1524)
				(type default)
			)
			(layer "F.SilkS")
		)
		(fp_line
			(start -1.2954 0.5842)
			(end -1.2954 -0.5842)
			(stroke
				(width 0.1524)
				(type default)
			)
			(layer "F.SilkS")
		)
		(fp_line
			(start 1.2954 -0.5842)
			(end 1.2954 0.5842)
			(stroke
				(width 0.1524)
				(type default)
			)
			(layer "F.SilkS")
		)
		(fp_line
			(start 1.2954 0.5842)
			(end -1.2954 0.5842)
			(stroke
				(width 0.1524)
				(type default)
			)
			(layer "F.SilkS")
		)
		(fp_line
			(start -1.1938 -0.406654)
			(end -0.8636 -0.406654)
			(stroke
				(width 0.1)
				(type default)
			)
			(layer "F.Fab")
		)
		(fp_line
			(start -1.1938 0.4064)
			(end -1.1938 -0.406654)
			(stroke
				(width 0.1)
				(type default)
			)
			(layer "F.Fab")
		)
		(fp_line
			(start -0.8636 -0.4572)
			(end 0.8636 -0.4572)
			(stroke
				(width 0.1)
				(type default)
			)
			(layer "F.Fab")
		)
		(fp_line
			(start -0.8636 -0.406654)
			(end -0.8636 -0.4572)
			(stroke
				(width 0.1)
				(type default)
			)
			(layer "F.Fab")
		)
		(fp_line
			(start -0.8636 0.4064)
			(end -1.1938 0.4064)
			(stroke
				(width 0.1)
				(type default)
			)
			(layer "F.Fab")
		)
		(fp_line
			(start -0.8636 0.4318)
			(end -0.8636 0.4064)
			(stroke
				(width 0.1)
				(type default)
			)
			(layer "F.Fab")
		)
		(fp_line
			(start -0.8636 0.4572)
			(end -0.8636 0.4318)
			(stroke
				(width 0.1)
				(type default)
			)
			(layer "F.Fab")
		)
		(fp_line
			(start 0.8636 -0.4572)
			(end 0.8636 -0.406654)
			(stroke
				(width 0.1)
				(type default)
			)
			(layer "F.Fab")
		)
		(fp_line
			(start 0.8636 -0.406654)
			(end 1.1938 -0.406654)
			(stroke
				(width 0.1)
				(type default)
			)
			(layer "F.Fab")
		)
		(fp_line
			(start 0.8636 0.4064)
			(end 0.8636 0.4572)
			(stroke
				(width 0.1)
				(type default)
			)
			(layer "F.Fab")
		)
		(fp_line
			(start 0.8636 0.4572)
			(end -0.8636 0.4572)
			(stroke
				(width 0.1)
				(type default)
			)
			(layer "F.Fab")
		)
		(fp_line
			(start 1.1938 -0.406654)
			(end 1.1938 0.4064)
			(stroke
				(width 0.1)
				(type default)
			)
			(layer "F.Fab")
		)
		(fp_line
			(start 1.1938 0.4064)
			(end 0.8636 0.4064)
			(stroke
				(width 0.1)
				(type default)
			)
			(layer "F.Fab")
		)
		(pad "1" smd rect
			(at -0.7366 0 270)
			(size 0.7112 0.8128)
			(layers "F.Cu" "F.Mask" "F.Paste")
			(net "XTAL_PCH_25M_IN_R")
		)
		(pad "2" smd rect
			(at 0.7366 0 270)
			(size 0.7112 0.8128)
			(layers "F.Cu" "F.Mask" "F.Paste")
			(net "XTAL_PCH_25M_OUT")
		)
	)
)
